# T6G (Grand Teton) — schematic netlist excerpt (pin names and nets, part order shuffled) for the footprints in the layout excerpt that follows; sources: Cadence DE-HDL packaged netlist, KiCad conversion of 04192023_DAF0TMB3IC0_F0TG_MB_C_brd_V02_OCP.brd

C2108  Q_CAP  22UF 4V 20% X6S  pkg C0402  page 74 : A = PVDDIO_P1 ; B = GND
R265  Q_RES  33 5% CHIP  pkg 0402LF  page 81 : A = FM_CPU1_FORCE_SELFREFRESH ; B = CPU1_FORCE_SELFREFRESH

(kicad_pcb
	(version 20260206)
	(generator "pcbnew")
	(generator_version "10.0")
	(general
		(thickness 1.6)
		(legacy_teardrops no)
	)
	(paper "A4")
	(title_block
		(title "04192023_DAF0TMB3IC0_F0TG_MB_C_brd_V02_OCP.brd")
		(comment 1 "Grand Teton / footprints 8231-8232 of 8354")
	)
	(layers
		(0 "F.Cu" signal "TOP")
		(4 "In1.Cu" signal "GND")
		(6 "In2.Cu" signal "IN1")
		(8 "In3.Cu" signal "GND1")
		(10 "In4.Cu" signal "IN2")
		(12 "In5.Cu" signal "GND2")
		(14 "In6.Cu" signal "IN3")
		(16 "In7.Cu" signal "GND3")
		(18 "In8.Cu" signal "VCC")
		(20 "In9.Cu" signal "VCC1")
		(22 "In10.Cu" signal "GND4")
		(24 "In11.Cu" signal "IN4")
		(26 "In12.Cu" signal "GND5")
		(28 "In13.Cu" signal "IN5")
		(30 "In14.Cu" signal "GND6")
		(32 "In15.Cu" signal "IN6")
		(34 "In16.Cu" signal "GND7")
		(2 "B.Cu" signal "BOTTOM")
		(9 "F.Adhes" user "F.Adhesive")
		(11 "B.Adhes" user "B.Adhesive")
		(13 "F.Paste" user "Package Geometry/Pastemask Top")
		(15 "B.Paste" user "Package Geometry/Pastemask Bottom")
		(5 "F.SilkS" user "Ref Des/Silkscreen Top")
		(7 "B.SilkS" user "Ref Des/Silkscreen Bottom")
		(1 "F.Mask" user "Board Geometry/Soldermask Top")
		(3 "B.Mask" user "Board Geometry/Soldermask Bottom")
		(17 "Dwgs.User" user "User.Drawings")
		(19 "Cmts.User" user "User.Comments")
		(21 "Eco1.User" user "User.Eco1")
		(23 "Eco2.User" user "User.Eco2")
		(25 "Edge.Cuts" user "Board Geometry/Outline")
		(27 "Margin" user)
		(31 "F.CrtYd" user "Package Geometry/Place Bound Top")
		(29 "B.CrtYd" user "Package Geometry/Place Bound Bottom")
		(35 "F.Fab" user "Ref Des/Assembly Top")
		(33 "B.Fab" user "Ref Des/Assembly Bottom")
	)
	(footprint ""
		(layer "B.Cu")
		(at 197.269608 -126.833376 180)
		(property "Reference" "R265"
			(at 0 0 0)
			(layer "B.SilkS")
			(hide yes)
			(effects
				(font
					(size 1.27 1.27)
				)
				(justify mirror)
			)
		)
		(property "Value" ""
			(at 0 0 0)
			(layer "B.Fab")
			(effects
				(font
					(size 1.27 1.27)
				)
				(justify mirror)
			)
		)
		(duplicate_pad_numbers_are_jumpers no)
		(fp_line
			(start 0.7874 0.4064)
			(end 0.7874 -0.4064)
			(stroke
				(width 0.1524)
				(type default)
			)
			(layer "B.SilkS")
		)
		(fp_line
			(start 0.7874 -0.4064)
			(end -0.7874 -0.4064)
			(stroke
				(width 0.1524)
				(type default)
			)
			(layer "B.SilkS")
		)
		(fp_line
			(start -0.7874 0.4064)
			(end 0.7874 0.4064)
			(stroke
				(width 0.1524)
				(type default)
			)
			(layer "B.SilkS")
		)
		(fp_line
			(start -0.7874 -0.4064)
			(end -0.7874 0.4064)
			(stroke
				(width 0.1524)
				(type default)
			)
			(layer "B.SilkS")
		)
		(fp_line
			(start 0.67945 0.3048)
			(end 0.67945 -0.305054)
			(stroke
				(width 0.1)
				(type default)
			)
			(layer "B.Fab")
		)
		(fp_line
			(start 0.67945 -0.305054)
			(end 0.12065 -0.305054)
			(stroke
				(width 0.1)
				(type default)
			)
			(layer "B.Fab")
		)
		(fp_line
			(start 0.12065 0.3048)
			(end 0.67945 0.3048)
			(stroke
				(width 0.1)
				(type default)
			)
			(layer "B.Fab")
		)
		(fp_line
			(start 0.12065 0.2794)
			(end 0.12065 0.3048)
			(stroke
				(width 0.1)
				(type default)
			)
			(layer "B.Fab")
		)
		(fp_line
			(start 0.12065 -0.2794)
			(end -0.12065 -0.2794)
			(stroke
				(width 0.1)
				(type default)
			)
			(layer "B.Fab")
		)
		(fp_line
			(start 0.12065 -0.305054)
			(end 0.12065 -0.2794)
			(stroke
				(width 0.1)
				(type default)
			)
			(layer "B.Fab")
		)
		(fp_line
			(start -0.120396 0.3048)
			(end -0.120396 0.2794)
			(stroke
				(width 0.1)
				(type default)
			)
			(layer "B.Fab")
		)
		(fp_line
			(start -0.120396 0.2794)
			(end 0.12065 0.2794)
			(stroke
				(width 0.1)
				(type default)
			)
			(layer "B.Fab")
		)
		(fp_line
			(start -0.12065 -0.2794)
			(end -0.12065 -0.3048)
			(stroke
				(width 0.1)
				(type default)
			)
			(layer "B.Fab")
		)
		(fp_line
			(start -0.12065 -0.3048)
			(end -0.67945 -0.3048)
			(stroke
				(width 0.1)
				(type default)
			)
			(layer "B.Fab")
		)
		(fp_line
			(start -0.67945 0.3048)
			(end -0.120396 0.3048)
			(stroke
				(width 0.1)
				(type default)
			)
			(layer "B.Fab")
		)
		(fp_line
			(start -0.67945 -0.3048)
			(end -0.67945 0.3048)
			(stroke
				(width 0.1)
				(type default)
			)
			(layer "B.Fab")
		)
		(pad "1" smd circle
			(at 0.40005 0)
			(size 0 0)
			(layers "B.Cu" "B.Mask" "B.Paste")
			(net "FM_CPU1_FORCE_SELFREFRESH")
		)
		(pad "2" smd circle
			(at -0.40005 0)
			(size 0 0)
			(layers "B.Cu" "B.Mask" "B.Paste")
			(net "CPU1_FORCE_SELFREFRESH")
		)
	)
	(footprint ""
		(layer "B.Cu")
		(at 98.493834 -265.045952)
		(property "Reference" "C2108"
			(at 0 0 0)
			(layer "B.SilkS")
			(hide yes)
			(effects
				(font
					(size 1.27 1.27)
				)
				(justify mirror)
			)
		)
		(property "Value" ""
			(at 0 0 0)
			(layer "B.Fab")
			(effects
				(font
					(size 1.27 1.27)
				)
				(justify mirror)
			)
		)
		(duplicate_pad_numbers_are_jumpers no)
		(fp_line
			(start -0.7874 -0.4064)
			(end -0.7874 0.4064)
			(stroke
				(width 0.1524)
				(type default)
			)
			(layer "B.SilkS")
		)
		(fp_line
			(start -0.7874 0.4064)
			(end 0.7874 0.4064)
			(stroke
				(width 0.1524)
				(type default)
			)
			(layer "B.SilkS")
		)
		(fp_line
			(start 0.7874 -0.4064)
			(end -0.7874 -0.4064)
			(stroke
				(width 0.1524)
				(type default)
			)
			(layer "B.SilkS")
		)
		(fp_line
			(start 0.7874 0.4064)
			(end 0.7874 -0.4064)
			(stroke
				(width 0.1524)
				(type default)
			)
			(layer "B.SilkS")
		)
		(fp_line
			(start -0.67945 -0.3048)
			(end -0.67945 0.3048)
			(stroke
				(width 0.1)
				(type default)
			)
			(layer "B.Fab")
		)
		(fp_line
			(start -0.67945 0.3048)
			(end -0.120396 0.3048)
			(stroke
				(width 0.1)
				(type default)
			)
			(layer "B.Fab")
		)
		(fp_line
			(start -0.12065 -0.3048)
			(end -0.67945 -0.3048)
			(stroke
				(width 0.1)
				(type default)
			)
			(layer "B.Fab")
		)
		(fp_line
			(start -0.12065 -0.2794)
			(end -0.12065 -0.3048)
			(stroke
				(width 0.1)
				(type default)
			)
			(layer "B.Fab")
		)
		(fp_line
			(start -0.120396 0.2794)
			(end 0.12065 0.2794)
			(stroke
				(width 0.1)
				(type default)
			)
			(layer "B.Fab")
		)
		(fp_line
			(start -0.120396 0.3048)
			(end -0.120396 0.2794)
			(stroke
				(width 0.1)
				(type default)
			)
			(layer "B.Fab")
		)
		(fp_line
			(start 0.12065 -0.305054)
			(end 0.12065 -0.2794)
			(stroke
				(width 0.1)
				(type default)
			)
			(layer "B.Fab")
		)
		(fp_line
			(start 0.12065 -0.2794)
			(end -0.12065 -0.2794)
			(stroke
				(width 0.1)
				(type default)
			)
			(layer "B.Fab")
		)
		(fp_line
			(start 0.12065 0.2794)
			(end 0.12065 0.3048)
			(stroke
				(width 0.1)
				(type default)
			)
			(layer "B.Fab")
		)
		(fp_line
			(start 0.12065 0.3048)
			(end 0.67945 0.3048)
			(stroke
				(width 0.1)
				(type default)
			)
			(layer "B.Fab")
		)
		(fp_line
			(start 0.67945 -0.305054)
			(end 0.12065 -0.305054)
			(stroke
				(width 0.1)
				(type default)
			)
			(layer "B.Fab")
		)
		(fp_line
			(start 0.67945 0.3048)
			(end 0.67945 -0.305054)
			(stroke
				(width 0.1)
				(type default)
			)
			(layer "B.Fab")
		)
		(pad "1" smd circle
			(at 0.40005 0 180)
			(size 0 0)
			(layers "B.Cu" "B.Mask" "B.Paste")
			(net "PVDDIO_P1")
		)
		(pad "2" smd circle
			(at -0.40005 0 180)
			(size 0 0)
			(layers "B.Cu" "B.Mask" "B.Paste")
			(net "GND")
		)
	)
)
